(kicad_pcb
	(version 20260206)
	(generator "pcbnew")
	(generator_version "10.0")
	(general
		(thickness 1.6)
		(legacy_teardrops no)
	)
	(paper "A4")
	(title_block
		(title "04192023_DAF0TMB3IC0_F0TG_MB_C_brd_V02_OCP.brd")
		(comment 1 "Grand Teton / footprints 2509-2514 of 8354")
	)
	(layers
		(0 "F.Cu" signal "TOP")
		(4 "In1.Cu" signal "GND")
		(6 "In2.Cu" signal "IN1")
		(8 "In3.Cu" signal "GND1")
		(10 "In4.Cu" signal "IN2")
		(12 "In5.Cu" signal "GND2")
		(14 "In6.Cu" signal "IN3")
		(16 "In7.Cu" signal "GND3")
		(18 "In8.Cu" signal "VCC")
		(20 "In9.Cu" signal "VCC1")
		(22 "In10.Cu" signal "GND4")
		(24 "In11.Cu" signal "IN4")
		(26 "In12.Cu" signal "GND5")
		(28 "In13.Cu" signal "IN5")
		(30 "In14.Cu" signal "GND6")
		(32 "In15.Cu" signal "IN6")
		(34 "In16.Cu" signal "GND7")
		(2 "B.Cu" signal "BOTTOM")
		(9 "F.Adhes" user "F.Adhesive")
		(11 "B.Adhes" user "B.Adhesive")
		(13 "F.Paste" user "Package Geometry/Pastemask Top")
		(15 "B.Paste" user "Package Geometry/Pastemask Bottom")
		(5 "F.SilkS" user "Ref Des/Silkscreen Top")
		(7 "B.SilkS" user "Ref Des/Silkscreen Bottom")
		(1 "F.Mask" user "Board Geometry/Soldermask Top")
		(3 "B.Mask" user "Board Geometry/Soldermask Bottom")
		(17 "Dwgs.User" user "User.Drawings")
		(19 "Cmts.User" user "User.Comments")
		(21 "Eco1.User" user "User.Eco1")
		(23 "Eco2.User" user "User.Eco2")
		(25 "Edge.Cuts" user "Board Geometry/Outline")
		(27 "Margin" user)
		(31 "F.CrtYd" user "Package Geometry/Place Bound Top")
		(29 "B.CrtYd" user "Package Geometry/Place Bound Bottom")
		(35 "F.Fab" user "Ref Des/Assembly Top")
		(33 "B.Fab" user "Ref Des/Assembly Bottom")
	)
	(footprint ""
		(layer "F.Cu")
		(at 63.575438 -31.887922 90)
		(property "Reference" "PR3849"
			(at 0 0 90)
			(layer "F.SilkS")
			(hide yes)
			(effects
				(font
					(size 1.27 1.27)
				)
			)
		)
		(property "Value" ""
			(at 0 0 90)
			(layer "F.Fab")
			(effects
				(font
					(size 1.27 1.27)
				)
			)
		)
		(duplicate_pad_numbers_are_jumpers no)
		(fp_line
			(start 0.7874 -0.4064)
			(end 0.7874 0.4064)
			(stroke
				(width 0.1524)
				(type default)
			)
			(layer "F.SilkS")
		)
		(fp_line
			(start -0.7874 -0.4064)
			(end 0.7874 -0.4064)
			(stroke
				(width 0.1524)
				(type default)
			)
			(layer "F.SilkS")
		)
		(fp_line
			(start 0.7874 0.4064)
			(end -0.7874 0.4064)
			(stroke
				(width 0.1524)
				(type default)
			)
			(layer "F.SilkS")
		)
		(fp_line
			(start -0.7874 0.4064)
			(end -0.7874 -0.4064)
			(stroke
				(width 0.1524)
				(type default)
			)
			(layer "F.SilkS")
		)
		(fp_line
			(start -0.12065 -0.305054)
			(end -0.12065 -0.2794)
			(stroke
				(width 0.1)
				(type default)
			)
			(layer "F.Fab")
		)
		(fp_line
			(start -0.67945 -0.305054)
			(end -0.12065 -0.305054)
			(stroke
				(width 0.1)
				(type default)
			)
			(layer "F.Fab")
		)
		(fp_line
			(start 0.67945 -0.3048)
			(end 0.67945 0.3048)
			(stroke
				(width 0.1)
				(type default)
			)
			(layer "F.Fab")
		)
		(fp_line
			(start 0.12065 -0.3048)
			(end 0.67945 -0.3048)
			(stroke
				(width 0.1)
				(type default)
			)
			(layer "F.Fab")
		)
		(fp_line
			(start 0.12065 -0.2794)
			(end 0.12065 -0.3048)
			(stroke
				(width 0.1)
				(type default)
			)
			(layer "F.Fab")
		)
		(fp_line
			(start -0.12065 -0.2794)
			(end 0.12065 -0.2794)
			(stroke
				(width 0.1)
				(type default)
			)
			(layer "F.Fab")
		)
		(fp_line
			(start 0.120396 0.2794)
			(end -0.12065 0.2794)
			(stroke
				(width 0.1)
				(type default)
			)
			(layer "F.Fab")
		)
		(fp_line
			(start -0.12065 0.2794)
			(end -0.12065 0.3048)
			(stroke
				(width 0.1)
				(type default)
			)
			(layer "F.Fab")
		)
		(fp_line
			(start 0.67945 0.3048)
			(end 0.120396 0.3048)
			(stroke
				(width 0.1)
				(type default)
			)
			(layer "F.Fab")
		)
		(fp_line
			(start 0.120396 0.3048)
			(end 0.120396 0.2794)
			(stroke
				(width 0.1)
				(type default)
			)
			(layer "F.Fab")
		)
		(fp_line
			(start -0.12065 0.3048)
			(end -0.67945 0.3048)
			(stroke
				(width 0.1)
				(type default)
			)
			(layer "F.Fab")
		)
		(fp_line
			(start -0.67945 0.3048)
			(end -0.67945 -0.305054)
			(stroke
				(width 0.1)
				(type default)
			)
			(layer "F.Fab")
		)
		(pad "1" smd circle
			(at -0.40005 0 90)
			(size 0 0)
			(layers "F.Cu" "F.Mask" "F.Paste")
			(net "P12V_OCP_IMON_2")
		)
		(pad "2" smd circle
			(at 0.40005 0 90)
			(size 0 0)
			(layers "F.Cu" "F.Mask" "F.Paste")
			(net "GND")
		)
	)
	(footprint ""
		(layer "F.Cu")
		(at 364.167166 -261.747762 -90)
		(property "Reference" "C2633"
			(at 0 0 270)
			(layer "F.SilkS")
			(hide yes)
			(effects
				(font
					(size 1.27 1.27)
				)
			)
		)
		(property "Value" ""
			(at 0 0 270)
			(layer "F.Fab")
			(effects
				(font
					(size 1.27 1.27)
				)
			)
		)
		(duplicate_pad_numbers_are_jumpers no)
		(fp_line
			(start -0.7874 0.4064)
			(end -0.7874 -0.4064)
			(stroke
				(width 0.1524)
				(type default)
			)
			(layer "F.SilkS")
		)
		(fp_line
			(start 0.7874 0.4064)
			(end -0.7874 0.4064)
			(stroke
				(width 0.1524)
				(type default)
			)
			(layer "F.SilkS")
		)
		(fp_line
			(start -0.7874 -0.4064)
			(end 0.7874 -0.4064)
			(stroke
				(width 0.1524)
				(type default)
			)
			(layer "F.SilkS")
		)
		(fp_line
			(start 0.7874 -0.4064)
			(end 0.7874 0.4064)
			(stroke
				(width 0.1524)
				(type default)
			)
			(layer "F.SilkS")
		)
		(fp_line
			(start -0.67945 0.3048)
			(end -0.67945 -0.305054)
			(stroke
				(width 0.1)
				(type default)
			)
			(layer "F.Fab")
		)
		(fp_line
			(start -0.12065 0.3048)
			(end -0.67945 0.3048)
			(stroke
				(width 0.1)
				(type default)
			)
			(layer "F.Fab")
		)
		(fp_line
			(start 0.120396 0.3048)
			(end 0.120396 0.2794)
			(stroke
				(width 0.1)
				(type default)
			)
			(layer "F.Fab")
		)
		(fp_line
			(start 0.67945 0.3048)
			(end 0.120396 0.3048)
			(stroke
				(width 0.1)
				(type default)
			)
			(layer "F.Fab")
		)
		(fp_line
			(start -0.12065 0.2794)
			(end -0.12065 0.3048)
			(stroke
				(width 0.1)
				(type default)
			)
			(layer "F.Fab")
		)
		(fp_line
			(start 0.120396 0.2794)
			(end -0.12065 0.2794)
			(stroke
				(width 0.1)
				(type default)
			)
			(layer "F.Fab")
		)
		(fp_line
			(start -0.12065 -0.2794)
			(end 0.12065 -0.2794)
			(stroke
				(width 0.1)
				(type default)
			)
			(layer "F.Fab")
		)
		(fp_line
			(start 0.12065 -0.2794)
			(end 0.12065 -0.3048)
			(stroke
				(width 0.1)
				(type default)
			)
			(layer "F.Fab")
		)
		(fp_line
			(start 0.12065 -0.3048)
			(end 0.67945 -0.3048)
			(stroke
				(width 0.1)
				(type default)
			)
			(layer "F.Fab")
		)
		(fp_line
			(start 0.67945 -0.3048)
			(end 0.67945 0.3048)
			(stroke
				(width 0.1)
				(type default)
			)
			(layer "F.Fab")
		)
		(fp_line
			(start -0.67945 -0.305054)
			(end -0.12065 -0.305054)
			(stroke
				(width 0.1)
				(type default)
			)
			(layer "F.Fab")
		)
		(fp_line
			(start -0.12065 -0.305054)
			(end -0.12065 -0.2794)
			(stroke
				(width 0.1)
				(type default)
			)
			(layer "F.Fab")
		)
		(pad "1" smd circle
			(at -0.40005 0 270)
			(size 0 0)
			(layers "F.Cu" "F.Mask" "F.Paste")
			(net "PVDD11_S3_P0")
		)
		(pad "2" smd circle
			(at 0.40005 0 270)
			(size 0 0)
			(layers "F.Cu" "F.Mask" "F.Paste")
			(net "GND")
		)
	)
	(footprint ""
		(layer "F.Cu")
		(at 392.531092 -378.95403 -90)
		(property "Reference" "C874"
			(at 0 0 270)
			(layer "F.SilkS")
			(hide yes)
			(effects
				(font
					(size 1.27 1.27)
				)
			)
		)
		(property "Value" ""
			(at 0 0 270)
			(layer "F.Fab")
			(effects
				(font
					(size 1.27 1.27)
				)
			)
		)
		(duplicate_pad_numbers_are_jumpers no)
		(fp_line
			(start -0.299974 0.150114)
			(end -0.299974 -0.150114)
			(stroke
				(width 0.1)
				(type default)
			)
			(layer "F.Fab")
		)
		(fp_line
			(start 0.299974 0.150114)
			(end -0.299974 0.150114)
			(stroke
				(width 0.1)
				(type default)
			)
			(layer "F.Fab")
		)
		(fp_line
			(start -0.299974 -0.150114)
			(end 0.299974 -0.150114)
			(stroke
				(width 0.1)
				(type default)
			)
			(layer "F.Fab")
		)
		(fp_line
			(start 0.299974 -0.150114)
			(end 0.299974 0.150114)
			(stroke
				(width 0.1)
				(type default)
			)
			(layer "F.Fab")
		)
		(pad "1" smd rect
			(at -0.2667 0 270)
			(size 0.3048 0.381)
			(layers "F.Cu" "F.Mask" "F.Paste")
			(net "P5E_CPU0_P3_TX_C_DN<13>")
		)
		(pad "2" smd rect
			(at 0.2667 0 270)
			(size 0.3048 0.381)
			(layers "F.Cu" "F.Mask" "F.Paste")
			(net "P5E_CPU0_P3_TX_DN<13>")
		)
	)
	(footprint ""
		(layer "F.Cu")
		(at 11.717782 -415.263584 90)
		(property "Reference" "PR6544"
			(at 0 0 90)
			(layer "F.SilkS")
			(hide yes)
			(effects
				(font
					(size 1.27 1.27)
				)
			)
		)
		(property "Value" ""
			(at 0 0 90)
			(layer "F.Fab")
			(effects
				(font
					(size 1.27 1.27)
				)
			)
		)
		(duplicate_pad_numbers_are_jumpers no)
		(fp_line
			(start 0.7874 -0.4064)
			(end 0.7874 0.4064)
			(stroke
				(width 0.1524)
				(type default)
			)
			(layer "F.SilkS")
		)
		(fp_line
			(start -0.7874 -0.4064)
			(end 0.7874 -0.4064)
			(stroke
				(width 0.1524)
				(type default)
			)
			(layer "F.SilkS")
		)
		(fp_line
			(start 0.7874 0.4064)
			(end -0.7874 0.4064)
			(stroke
				(width 0.1524)
				(type default)
			)
			(layer "F.SilkS")
		)
		(fp_line
			(start -0.7874 0.4064)
			(end -0.7874 -0.4064)
			(stroke
				(width 0.1524)
				(type default)
			)
			(layer "F.SilkS")
		)
		(fp_line
			(start -0.12065 -0.305054)
			(end -0.12065 -0.2794)
			(stroke
				(width 0.1)
				(type default)
			)
			(layer "F.Fab")
		)
		(fp_line
			(start -0.67945 -0.305054)
			(end -0.12065 -0.305054)
			(stroke
				(width 0.1)
				(type default)
			)
			(layer "F.Fab")
		)
		(fp_line
			(start 0.67945 -0.3048)
			(end 0.67945 0.3048)
			(stroke
				(width 0.1)
				(type default)
			)
			(layer "F.Fab")
		)
		(fp_line
			(start 0.12065 -0.3048)
			(end 0.67945 -0.3048)
			(stroke
				(width 0.1)
				(type default)
			)
			(layer "F.Fab")
		)
		(fp_line
			(start 0.12065 -0.2794)
			(end 0.12065 -0.3048)
			(stroke
				(width 0.1)
				(type default)
			)
			(layer "F.Fab")
		)
		(fp_line
			(start -0.12065 -0.2794)
			(end 0.12065 -0.2794)
			(stroke
				(width 0.1)
				(type default)
			)
			(layer "F.Fab")
		)
		(fp_line
			(start 0.120396 0.2794)
			(end -0.12065 0.2794)
			(stroke
				(width 0.1)
				(type default)
			)
			(layer "F.Fab")
		)
		(fp_line
			(start -0.12065 0.2794)
			(end -0.12065 0.3048)
			(stroke
				(width 0.1)
				(type default)
			)
			(layer "F.Fab")
		)
		(fp_line
			(start 0.67945 0.3048)
			(end 0.120396 0.3048)
			(stroke
				(width 0.1)
				(type default)
			)
			(layer "F.Fab")
		)
		(fp_line
			(start 0.120396 0.3048)
			(end 0.120396 0.2794)
			(stroke
				(width 0.1)
				(type default)
			)
			(layer "F.Fab")
		)
		(fp_line
			(start -0.12065 0.3048)
			(end -0.67945 0.3048)
			(stroke
				(width 0.1)
				(type default)
			)
			(layer "F.Fab")
		)
		(fp_line
			(start -0.67945 0.3048)
			(end -0.67945 -0.305054)
			(stroke
				(width 0.1)
				(type default)
			)
			(layer "F.Fab")
		)
		(pad "1" smd circle
			(at -0.40005 0 90)
			(size 0 0)
			(layers "F.Cu" "F.Mask" "F.Paste")
			(net "NC_P0V9_RETIMER_CPU1_IMON8")
		)
		(pad "2" smd circle
			(at 0.40005 0 90)
			(size 0 0)
			(layers "F.Cu" "F.Mask" "F.Paste")
			(net "GND")
		)
	)
	(footprint ""
		(layer "F.Cu")
		(at 145.128488 -394.166852 -90)
		(property "Reference" "R886"
			(at 0 0 270)
			(layer "F.SilkS")
			(hide yes)
			(effects
				(font
					(size 1.27 1.27)
				)
			)
		)
		(property "Value" ""
			(at 0 0 270)
			(layer "F.Fab")
			(effects
				(font
					(size 1.27 1.27)
				)
			)
		)
		(duplicate_pad_numbers_are_jumpers no)
		(fp_line
			(start -0.32512 0.175006)
			(end -0.32512 -0.175006)
			(stroke
				(width 0.1)
				(type default)
			)
			(layer "F.Fab")
		)
		(fp_line
			(start 0.32512 0.175006)
			(end -0.32512 0.175006)
			(stroke
				(width 0.1)
				(type default)
			)
			(layer "F.Fab")
		)
		(fp_line
			(start -0.32512 -0.175006)
			(end 0.32512 -0.175006)
			(stroke
				(width 0.1)
				(type default)
			)
			(layer "F.Fab")
		)
		(fp_line
			(start 0.32512 -0.175006)
			(end 0.32512 0.175006)
			(stroke
				(width 0.1)
				(type default)
			)
			(layer "F.Fab")
		)
		(pad "1" smd rect
			(at -0.2667 0 270)
			(size 0.3048 0.381)
			(layers "F.Cu" "F.Mask" "F.Paste")
			(net "MODE_RT_CPU1_P2")
		)
		(pad "2" smd rect
			(at 0.2667 0 90)
			(size 0.3048 0.381)
			(layers "F.Cu" "F.Mask" "F.Paste")
			(net "GND")
		)
	)
	(footprint ""
		(layer "F.Cu")
		(at 286.928052 -119.207026)
		(property "Reference" "U36"
			(at -2.1844 -4.587748 0)
			(unlocked yes)
			(layer "F.SilkS")
			(effects
				(font
					(size 0.7874 0.5842)
					(thickness 0.1524)
				)
				(justify left)
			)
		)
		(property "Value" ""
			(at 0 0 0)
			(layer "F.Fab")
			(effects
				(font
					(size 1.27 1.27)
				)
			)
		)
		(duplicate_pad_numbers_are_jumpers no)
		(fp_line
			(start -1.8542 -3.949954)
			(end -1.8542 3.949954)
			(stroke
				(width 0.1524)
				(type default)
			)
			(layer "F.SilkS")
		)
		(fp_line
			(start -1.8542 3.949954)
			(end 1.8542 3.949954)
			(stroke
				(width 0.1524)
				(type default)
			)
			(layer "F.SilkS")
		)
		(fp_line
			(start -1.282954 -3.949954)
			(end -1.8542 -3.949954)
			(stroke
				(width 0.1524)
				(type default)
			)
			(layer "F.SilkS")
		)
		(fp_line
			(start 0 -2.667)
			(end -1.282954 -3.949954)
			(stroke
				(width 0.1524)
				(type default)
			)
			(layer "F.SilkS")
		)
		(fp_line
			(start 1.282954 -3.949954)
			(end 0 -2.667)
			(stroke
				(width 0.1524)
				(type default)
			)
			(layer "F.SilkS")
		)
		(fp_line
			(start 1.8542 -3.949954)
			(end 1.282954 -3.949954)
			(stroke
				(width 0.1524)
				(type default)
			)
			(layer "F.SilkS")
		)
		(fp_line
			(start 1.8542 3.949954)
			(end 1.8542 -3.949954)
			(stroke
				(width 0.1524)
				(type default)
			)
			(layer "F.SilkS")
		)
		(fp_poly
			(pts
				(xy -3.074416 -3.996182) (xy -3.582416 -5.012182) (xy -2.566416 -5.012182)
			)
			(stroke
				(width 0)
				(type default)
			)
			(fill yes)
			(layer "F.SilkS")
		)
		(fp_line
			(start -2.249932 -3.949954)
			(end -2.249932 3.949954)
			(stroke
				(width 0.1)
				(type default)
			)
			(layer "F.Fab")
		)
		(fp_line
			(start -2.249932 3.949954)
			(end 2.249932 3.949954)
			(stroke
				(width 0.1)
				(type default)
			)
			(layer "F.Fab")
		)
		(fp_line
			(start 2.249932 -3.949954)
			(end -2.249932 -3.949954)
			(stroke
				(width 0.1)
				(type default)
			)
			(layer "F.Fab")
		)
		(fp_line
			(start 2.249932 3.949954)
			(end 2.249932 -3.949954)
			(stroke
				(width 0.1)
				(type default)
			)
			(layer "F.Fab")
		)
		(fp_poly
			(pts
				(xy -4.8006 -4.08305) (xy -4.8006 -3.06705) (xy -3.7846 -3.57505)
			)
			(stroke
				(width 0)
				(type default)
			)
			(fill yes)
			(layer "F.Fab")
		)
		(pad "1" smd rect
			(at -2.800096 -3.57505 270)
			(size 0.3048 1.6002)
			(layers "F.Cu" "F.Mask" "F.Paste")
			(net "PCA9548_PCIE3_ADDR0")
		)
		(pad "2" smd rect
			(at -2.800096 -2.925064 270)
			(size 0.3048 1.6002)
			(layers "F.Cu" "F.Mask" "F.Paste")
			(net "PCA9548_PCIE3_ADDR1")
		)
		(pad "3" smd rect
			(at -2.800096 -2.275078 270)
			(size 0.3048 1.6002)
			(layers "F.Cu" "F.Mask" "F.Paste")
			(net "PU_RST_SMB_PCIE0_N")
		)
		(pad "4" smd rect
			(at -2.800096 -1.625092 270)
			(size 0.3048 1.6002)
			(layers "F.Cu" "F.Mask" "F.Paste")
			(net "SMB_USB_CPU0_HUB1_SDA_R")
		)
		(pad "5" smd rect
			(at -2.800096 -0.975106 270)
			(size 0.3048 1.6002)
			(layers "F.Cu" "F.Mask" "F.Paste")
			(net "SMB_USB_CPU0_HUB1_SCL_R")
		)
		(pad "6" smd rect
			(at -2.800096 -0.32512 270)
			(size 0.3048 1.6002)
			(layers "F.Cu" "F.Mask" "F.Paste")
			(net "SMB_IOEXP_3V3AUX_SDA_R")
		)
		(pad "7" smd rect
			(at -2.800096 0.32512 270)
			(size 0.3048 1.6002)
			(layers "F.Cu" "F.Mask" "F.Paste")
			(net "SMB_IOEXP_3V3AUX_SCL_R")
		)
		(pad "8" smd rect
			(at -2.800096 0.975106 270)
			(size 0.3048 1.6002)
			(layers "F.Cu" "F.Mask" "F.Paste")
			(net "SMB_PCIE0_3V3AUX_SDA_R3")
		)
		(pad "9" smd rect
			(at -2.800096 1.625092 270)
			(size 0.3048 1.6002)
			(layers "F.Cu" "F.Mask" "F.Paste")
			(net "SMB_PCIE0_3V3AUX_SCL_R3")
		)
		(pad "10" smd rect
			(at -2.800096 2.275078 270)
			(size 0.3048 1.6002)
			(layers "F.Cu" "F.Mask" "F.Paste")
			(net "SMB_PCIE0_3V3AUX_SDA_R5")
		)
		(pad "11" smd rect
			(at -2.800096 2.925064 270)
			(size 0.3048 1.6002)
			(layers "F.Cu" "F.Mask" "F.Paste")
			(net "SMB_PCIE0_3V3AUX_SCL_R5")
		)
		(pad "12" smd rect
			(at -2.800096 3.57505 270)
			(size 0.3048 1.6002)
			(layers "F.Cu" "F.Mask" "F.Paste")
			(net "GND")
		)
		(pad "13" smd rect
			(at 2.800096 3.57505 270)
			(size 0.3048 1.6002)
			(layers "F.Cu" "F.Mask" "F.Paste")
			(net "SMB_BMC_SWB_SDA_R4")
		)
		(pad "14" smd rect
			(at 2.800096 2.925064 270)
			(size 0.3048 1.6002)
			(layers "F.Cu" "F.Mask" "F.Paste")
			(net "SMB_BMC_SWB_SCL_R4")
		)
		(pad "15" smd rect
			(at 2.800096 2.275078 270)
			(size 0.3048 1.6002)
			(layers "F.Cu" "F.Mask" "F.Paste")
			(net "SMB_FRU_3V3AUX_SDA_R")
		)
		(pad "16" smd rect
			(at 2.800096 1.625092 270)
			(size 0.3048 1.6002)
			(layers "F.Cu" "F.Mask" "F.Paste")
			(net "SMB_FRU_3V3AUX_SCL_R")
		)
		(pad "17" smd rect
			(at 2.800096 0.975106 270)
			(size 0.3048 1.6002)
			(layers "F.Cu" "F.Mask" "F.Paste")
			(net "SMB_INA230_3V3AUX_SDA_R")
		)
		(pad "18" smd rect
			(at 2.800096 0.32512 270)
			(size 0.3048 1.6002)
			(layers "F.Cu" "F.Mask" "F.Paste")
			(net "SMB_INA230_3V3AUX_SCL_R")
		)
		(pad "19" smd rect
			(at 2.800096 -0.32512 270)
			(size 0.3048 1.6002)
			(layers "F.Cu" "F.Mask" "F.Paste")
			(net "Net_10757")
		)
		(pad "20" smd rect
			(at 2.800096 -0.975106 270)
			(size 0.3048 1.6002)
			(layers "F.Cu" "F.Mask" "F.Paste")
			(net "Net_10758")
		)
		(pad "21" smd rect
			(at 2.800096 -1.625092 270)
			(size 0.3048 1.6002)
			(layers "F.Cu" "F.Mask" "F.Paste")
			(net "PCA9548_PCIE3_ADDR2")
		)
		(pad "22" smd rect
			(at 2.800096 -2.275078 270)
			(size 0.3048 1.6002)
			(layers "F.Cu" "F.Mask" "F.Paste")
			(net "SMB_PCIE0_3V3AUX_SCL_R")
		)
		(pad "23" smd rect
			(at 2.800096 -2.925064 270)
			(size 0.3048 1.6002)
			(layers "F.Cu" "F.Mask" "F.Paste")
			(net "SMB_PCIE0_3V3AUX_SDA_R")
		)
		(pad "24" smd rect
			(at 2.800096 -3.57505 270)
			(size 0.3048 1.6002)
			(layers "F.Cu" "F.Mask" "F.Paste")
			(net "P3V3_AUX")
		)
	)
)
